FILE_TYPE = MACRO_DRAWING;
SET COLOR_WIRE YELLOW;
SET COLOR_PROP ORANGE;
SET COLOR_DOT WHITE;
SET COLOR_ARC YELLOW;
SET COLOR_BODY GREEN;
SET COLOR_NOTE PURPLE;
SET PROP_DISPLAY VALUE;
SET PAGE_NUMBER P409;
FORCEADD VCC_CORE..1
(-4900 5025);
FORCEPROP 3 LASTPIN (-4900 4975) SIG_NAME P0V9_CPU0_RT1_2A\g
J 0
(-4890 4985);
DISPLAY 0.659574 (-4890 4985);
PAINT MONO (-4890 4985);
DISPLAY INVISIBLE (-4890 4985);
FORCEPROP 1 LAST HDL_POWER P0V9_CPU0_RT1_2A
J 1
(-4900 5075);
DISPLAY 0.617021 (-4900 5075);
PAINT SKYBLUE (-4900 5075);
FORCEPROP 2 LAST CDS_LIB pure_quanta_power
J 0
(-4900 5025);
DISPLAY INVISIBLE (-4900 5025);
FORCEPROP 1 LAST PATH I10
J 0
(-4850 5050);
DISPLAY 0.872340 (-4850 5050);
PAINT AQUA (-4850 5050);
DISPLAY INVISIBLE (-4850 5050);
FORCEADD UNIVERSAL_GND..1
(-3350 1325);
FORCEPROP 3 LASTPIN (-3350 1375) SIG_NAME GND\g
J 0
(-3340 1385);
DISPLAY 0.659574 (-3340 1385);
PAINT MONO (-3340 1385);
DISPLAY INVISIBLE (-3340 1385);
FORCEPROP 2 LAST CDS_LIB pure_quanta_power
J 0
(-3350 1325);
DISPLAY INVISIBLE (-3350 1325);
FORCEPROP 1 LAST HDL_POWER GND
J 1
(-3325 1250);
DISPLAY 0.872340 (-3325 1250);
PAINT GREEN (-3325 1250);
DISPLAY INVISIBLE (-3325 1250);
FORCEPROP 1 LAST PATH I11
J 0
(-3275 1325);
DISPLAY 0.872340 (-3275 1325);
PAINT AQUA (-3275 1325);
DISPLAY INVISIBLE (-3275 1325);
FORCEADD UNIVERSAL_GND..1
(-1675 950);
FORCEPROP 3 LASTPIN (-1675 1000) SIG_NAME GND\g
J 0
(-1665 1010);
DISPLAY 0.659574 (-1665 1010);
PAINT MONO (-1665 1010);
DISPLAY INVISIBLE (-1665 1010);
FORCEPROP 2 LAST CDS_LIB pure_quanta_power
J 0
(-1675 950);
DISPLAY INVISIBLE (-1675 950);
FORCEPROP 1 LAST HDL_POWER GND
J 1
(-1650 875);
DISPLAY 0.872340 (-1650 875);
PAINT GREEN (-1650 875);
DISPLAY INVISIBLE (-1650 875);
FORCEPROP 1 LAST PATH I12
J 0
(-1600 950);
DISPLAY 0.872340 (-1600 950);
PAINT AQUA (-1600 950);
DISPLAY INVISIBLE (-1600 950);
FORCEADD Q_RES..2
(-1675 1250);
FORCEPROP 1 LAST LOCATION R1042
J 0
(-1630 1375);
DISPLAY 0.978723 (-1630 1375);
FORCEPROP 0 LAST $SEC 1
J 0
(-1625 1425);
DISPLAY 0.680851 (-1625 1425);
PAINT MONO (-1625 1425);
DISPLAY INVISIBLE (-1625 1425);
FORCEPROP 0 LAST CDS_SEC 1
J 0
(-1625 1425);
DISPLAY 0.680851 (-1625 1425);
DISPLAY INVISIBLE (-1625 1425);
FORCEPROP 1 LASTPIN (-1675 1350) $PN 1
J 0
(-1670 1312);
DISPLAY 0.787234 (-1670 1312);
PAINT MONO (-1670 1312);
FORCEPROP 1 LASTPIN (-1675 1150) $PN 2
J 0
(-1670 1160);
DISPLAY 0.787234 (-1670 1160);
PAINT MONO (-1670 1160);
FORCEPROP 1 LAST MATERIAL CHIP
J 0
(-1635 1175);
DISPLAY 0.978723 (-1635 1175);
FORCEPROP 1 LAST WATTAGE 1/20W
J 0
(-1635 1225);
DISPLAY 0.978723 (-1635 1225);
FORCEPROP 1 LAST TOLERANCE 5%
J 0
(-1630 1275);
DISPLAY 0.978723 (-1630 1275);
FORCEPROP 1 LAST VALUE 0
J 0
(-1630 1325);
DISPLAY 0.978723 (-1630 1325);
FORCEPROP 1 LAST PACK_TYPE 0201LF
J 0
(-1635 1075);
DISPLAY 0.978723 (-1635 1075);
FORCEPROP 2 LAST CDS_LIB pure_quanta
J 0
(-1675 1250);
DISPLAY INVISIBLE (-1675 1250);
FORCEPROP 1 LAST PATH I13
J 0
(-1625 1425);
DISPLAY 0.978723 (-1625 1425);
PAINT WHITE (-1625 1425);
DISPLAY INVISIBLE (-1625 1425);
FORCEPROP 1 LAST PART_NUMBER CS00001JE10
J 0
(-1635 1125);
DISPLAY 0.978723 (-1635 1125);
DISPLAY INVISIBLE (-1635 1125);
FORCEADD UNIVERSAL_GND..1
(-1525 1500);
FORCEPROP 3 LASTPIN (-1525 1550) SIG_NAME GND\g
J 0
(-1515 1560);
DISPLAY 0.659574 (-1515 1560);
PAINT MONO (-1515 1560);
DISPLAY INVISIBLE (-1515 1560);
FORCEPROP 2 LAST CDS_LIB pure_quanta_power
J 0
(-1525 1500);
DISPLAY INVISIBLE (-1525 1500);
FORCEPROP 1 LAST HDL_POWER GND
J 1
(-1500 1425);
DISPLAY 0.872340 (-1500 1425);
PAINT GREEN (-1500 1425);
DISPLAY INVISIBLE (-1500 1425);
FORCEPROP 1 LAST PATH I14
J 0
(-1450 1500);
DISPLAY 0.872340 (-1450 1500);
PAINT AQUA (-1450 1500);
DISPLAY INVISIBLE (-1450 1500);
FORCEADD Q_RES..2
(-1525 1800);
FORCEPROP 1 LAST LOCATION R1043
J 0
(-1480 1925);
DISPLAY 0.978723 (-1480 1925);
FORCEPROP 0 LAST $SEC 1
J 0
(-1475 1975);
DISPLAY 0.680851 (-1475 1975);
PAINT MONO (-1475 1975);
DISPLAY INVISIBLE (-1475 1975);
FORCEPROP 0 LAST CDS_SEC 1
J 0
(-1475 1975);
DISPLAY 0.680851 (-1475 1975);
DISPLAY INVISIBLE (-1475 1975);
FORCEPROP 1 LASTPIN (-1525 1900) $PN 1
J 0
(-1520 1862);
DISPLAY 0.787234 (-1520 1862);
PAINT MONO (-1520 1862);
FORCEPROP 1 LASTPIN (-1525 1700) $PN 2
J 0
(-1520 1710);
DISPLAY 0.787234 (-1520 1710);
PAINT MONO (-1520 1710);
FORCEPROP 1 LAST WATTAGE 1/20W
J 0
(-1485 1775);
DISPLAY 0.978723 (-1485 1775);
FORCEPROP 1 LAST TOLERANCE 5%
J 0
(-1480 1825);
DISPLAY 0.978723 (-1480 1825);
FORCEPROP 1 LAST MATERIAL CHIP
J 0
(-1485 1725);
DISPLAY 0.978723 (-1485 1725);
FORCEPROP 1 LAST PACK_TYPE 0201LF
J 0
(-1485 1625);
DISPLAY 0.978723 (-1485 1625);
FORCEPROP 1 LAST VALUE 0
J 0
(-1480 1875);
DISPLAY 0.978723 (-1480 1875);
FORCEPROP 2 LAST CDS_LIB pure_quanta
J 0
(-1525 1800);
DISPLAY INVISIBLE (-1525 1800);
FORCEPROP 1 LAST PATH I15
J 0
(-1475 1975);
DISPLAY 0.978723 (-1475 1975);
PAINT WHITE (-1475 1975);
DISPLAY INVISIBLE (-1475 1975);
FORCEPROP 1 LAST PART_NUMBER CS00001JE10
J 0
(-1485 1675);
DISPLAY 0.978723 (-1485 1675);
DISPLAY INVISIBLE (-1485 1675);
FORCEADD UNIVERSAL_GND..1
(-1300 2050);
FORCEPROP 3 LASTPIN (-1300 2100) SIG_NAME GND\g
J 0
(-1290 2110);
DISPLAY 0.659574 (-1290 2110);
PAINT MONO (-1290 2110);
DISPLAY INVISIBLE (-1290 2110);
FORCEPROP 2 LAST CDS_LIB pure_quanta_power
J 0
(-1300 2050);
DISPLAY INVISIBLE (-1300 2050);
FORCEPROP 1 LAST HDL_POWER GND
J 1
(-1275 1975);
DISPLAY 0.872340 (-1275 1975);
PAINT GREEN (-1275 1975);
DISPLAY INVISIBLE (-1275 1975);
FORCEPROP 1 LAST PATH I16
J 0
(-1225 2050);
DISPLAY 0.872340 (-1225 2050);
PAINT AQUA (-1225 2050);
DISPLAY INVISIBLE (-1225 2050);
FORCEADD PT5161LRS..5
(-2650 3575);
FORCEPROP 1 LAST LOCATION U6011
J 0
(-3000 5900);
DISPLAY 0.723404 (-3000 5900);
PAINT SKYBLUE (-3000 5900);
FORCEPROP 0 LAST $SEC 5
J 0
(-3000 6050);
DISPLAY 0.680851 (-3000 6050);
PAINT MONO (-3000 6050);
DISPLAY INVISIBLE (-3000 6050);
FORCEPROP 0 LAST CDS_SEC 5
J 0
(-3000 6050);
DISPLAY 0.680851 (-3000 6050);
DISPLAY INVISIBLE (-3000 6050);
FORCEPROP 0 LASTPIN (-3150 5575) $PN AC13
J 2
(-3160 5585);
DISPLAY 0.680851 (-3160 5585);
PAINT MONO (-3160 5585);
FORCEPROP 0 LASTPIN (-3150 5525) $PN AC22
J 2
(-3160 5535);
DISPLAY 0.680851 (-3160 5535);
PAINT MONO (-3160 5535);
FORCEPROP 0 LASTPIN (-3150 5475) $PN AC32
J 2
(-3160 5485);
DISPLAY 0.680851 (-3160 5485);
PAINT MONO (-3160 5485);
FORCEPROP 0 LASTPIN (-3150 5425) $PN AC4
J 2
(-3160 5435);
DISPLAY 0.680851 (-3160 5435);
PAINT MONO (-3160 5435);
FORCEPROP 0 LASTPIN (-3150 5375) $PN AD2
J 2
(-3160 5385);
DISPLAY 0.680851 (-3160 5385);
PAINT MONO (-3160 5385);
FORCEPROP 0 LASTPIN (-3150 5325) $PN AD34
J 2
(-3160 5335);
DISPLAY 0.680851 (-3160 5335);
PAINT MONO (-3160 5335);
FORCEPROP 0 LASTPIN (-3150 5275) $PN AE1
J 2
(-3160 5285);
DISPLAY 0.680851 (-3160 5285);
PAINT MONO (-3160 5285);
FORCEPROP 0 LASTPIN (-3150 5225) $PN AE35
J 2
(-3160 5235);
DISPLAY 0.680851 (-3160 5235);
PAINT MONO (-3160 5235);
FORCEPROP 0 LASTPIN (-3150 5175) $PN AK13
J 2
(-3160 5185);
DISPLAY 0.680851 (-3160 5185);
PAINT MONO (-3160 5185);
FORCEPROP 0 LASTPIN (-3150 5125) $PN AK22
J 2
(-3160 5135);
DISPLAY 0.680851 (-3160 5135);
PAINT MONO (-3160 5135);
FORCEPROP 0 LASTPIN (-3150 5075) $PN AK32
J 2
(-3160 5085);
DISPLAY 0.680851 (-3160 5085);
PAINT MONO (-3160 5085);
FORCEPROP 0 LASTPIN (-3150 5025) $PN AK4
J 2
(-3160 5035);
DISPLAY 0.680851 (-3160 5035);
PAINT MONO (-3160 5035);
FORCEPROP 0 LASTPIN (-3150 4975) $PN AL2
J 2
(-3160 4985);
DISPLAY 0.680851 (-3160 4985);
PAINT MONO (-3160 4985);
FORCEPROP 0 LASTPIN (-3150 4925) $PN AL34
J 2
(-3160 4935);
DISPLAY 0.680851 (-3160 4935);
PAINT MONO (-3160 4935);
FORCEPROP 0 LASTPIN (-3150 4875) $PN AM1
J 2
(-3160 4885);
DISPLAY 0.680851 (-3160 4885);
PAINT MONO (-3160 4885);
FORCEPROP 0 LASTPIN (-3150 4825) $PN AM35
J 2
(-3160 4835);
DISPLAY 0.680851 (-3160 4835);
PAINT MONO (-3160 4835);
FORCEPROP 0 LASTPIN (-3150 4775) $PN AU13
J 2
(-3160 4785);
DISPLAY 0.680851 (-3160 4785);
PAINT MONO (-3160 4785);
FORCEPROP 0 LASTPIN (-3150 4725) $PN AU22
J 2
(-3160 4735);
DISPLAY 0.680851 (-3160 4735);
PAINT MONO (-3160 4735);
FORCEPROP 0 LASTPIN (-3150 4675) $PN AU32
J 2
(-3160 4685);
DISPLAY 0.680851 (-3160 4685);
PAINT MONO (-3160 4685);
FORCEPROP 0 LASTPIN (-3150 4625) $PN AU4
J 2
(-3160 4635);
DISPLAY 0.680851 (-3160 4635);
PAINT MONO (-3160 4635);
FORCEPROP 0 LASTPIN (-3150 4575) $PN AV2
J 2
(-3160 4585);
DISPLAY 0.680851 (-3160 4585);
PAINT MONO (-3160 4585);
FORCEPROP 0 LASTPIN (-3150 4525) $PN AV34
J 2
(-3160 4535);
DISPLAY 0.680851 (-3160 4535);
PAINT MONO (-3160 4535);
FORCEPROP 0 LASTPIN (-3150 4475) $PN AW1
J 2
(-3160 4485);
DISPLAY 0.680851 (-3160 4485);
PAINT MONO (-3160 4485);
FORCEPROP 0 LASTPIN (-3150 4425) $PN AW35
J 2
(-3160 4435);
DISPLAY 0.680851 (-3160 4435);
PAINT MONO (-3160 4435);
FORCEPROP 0 LASTPIN (-3150 4375) $PN B19
J 2
(-3160 4385);
DISPLAY 0.680851 (-3160 4385);
PAINT MONO (-3160 4385);
FORCEPROP 0 LASTPIN (-3150 4325) $PN BD13
J 2
(-3160 4335);
DISPLAY 0.680851 (-3160 4335);
PAINT MONO (-3160 4335);
FORCEPROP 0 LASTPIN (-3150 4275) $PN BD22
J 2
(-3160 4285);
DISPLAY 0.680851 (-3160 4285);
PAINT MONO (-3160 4285);
FORCEPROP 0 LASTPIN (-3150 4225) $PN BD32
J 2
(-3160 4235);
DISPLAY 0.680851 (-3160 4235);
PAINT MONO (-3160 4235);
FORCEPROP 0 LASTPIN (-3150 4175) $PN BD4
J 2
(-3160 4185);
DISPLAY 0.680851 (-3160 4185);
PAINT MONO (-3160 4185);
FORCEPROP 0 LASTPIN (-3150 4125) $PN BE2
J 2
(-3160 4135);
DISPLAY 0.680851 (-3160 4135);
PAINT MONO (-3160 4135);
FORCEPROP 0 LASTPIN (-3150 4075) $PN BE34
J 2
(-3160 4085);
DISPLAY 0.680851 (-3160 4085);
PAINT MONO (-3160 4085);
FORCEPROP 0 LASTPIN (-3150 4025) $PN BF1
J 2
(-3160 4035);
DISPLAY 0.680851 (-3160 4035);
PAINT MONO (-3160 4035);
FORCEPROP 0 LASTPIN (-3150 3975) $PN BF35
J 2
(-3160 3985);
DISPLAY 0.680851 (-3160 3985);
PAINT MONO (-3160 3985);
FORCEPROP 0 LASTPIN (-3150 3925) $PN BL13
J 2
(-3160 3935);
DISPLAY 0.680851 (-3160 3935);
PAINT MONO (-3160 3935);
FORCEPROP 0 LASTPIN (-3150 3875) $PN BL22
J 2
(-3160 3885);
DISPLAY 0.680851 (-3160 3885);
PAINT MONO (-3160 3885);
FORCEPROP 0 LASTPIN (-3150 3825) $PN BL32
J 2
(-3160 3835);
DISPLAY 0.680851 (-3160 3835);
PAINT MONO (-3160 3835);
FORCEPROP 0 LASTPIN (-3150 3775) $PN BL4
J 2
(-3160 3785);
DISPLAY 0.680851 (-3160 3785);
PAINT MONO (-3160 3785);
FORCEPROP 0 LASTPIN (-3150 3725) $PN BM2
J 2
(-3160 3735);
DISPLAY 0.680851 (-3160 3735);
PAINT MONO (-3160 3735);
FORCEPROP 0 LASTPIN (-3150 3675) $PN BM34
J 2
(-3160 3685);
DISPLAY 0.680851 (-3160 3685);
PAINT MONO (-3160 3685);
FORCEPROP 0 LASTPIN (-3150 3625) $PN BN1
J 2
(-3160 3635);
DISPLAY 0.680851 (-3160 3635);
PAINT MONO (-3160 3635);
FORCEPROP 0 LASTPIN (-3150 3575) $PN BN35
J 2
(-3160 3585);
DISPLAY 0.680851 (-3160 3585);
PAINT MONO (-3160 3585);
FORCEPROP 0 LASTPIN (-3150 3525) $PN BV13
J 2
(-3160 3535);
DISPLAY 0.680851 (-3160 3535);
PAINT MONO (-3160 3535);
FORCEPROP 0 LASTPIN (-3150 3475) $PN BV22
J 2
(-3160 3485);
DISPLAY 0.680851 (-3160 3485);
PAINT MONO (-3160 3485);
FORCEPROP 0 LASTPIN (-3150 3425) $PN BV32
J 2
(-3160 3435);
DISPLAY 0.680851 (-3160 3435);
PAINT MONO (-3160 3435);
FORCEPROP 0 LASTPIN (-3150 3375) $PN BV4
J 2
(-3160 3385);
DISPLAY 0.680851 (-3160 3385);
PAINT MONO (-3160 3385);
FORCEPROP 0 LASTPIN (-3150 3325) $PN BW2
J 2
(-3160 3335);
DISPLAY 0.680851 (-3160 3335);
PAINT MONO (-3160 3335);
FORCEPROP 0 LASTPIN (-3150 3275) $PN BW34
J 2
(-3160 3285);
DISPLAY 0.680851 (-3160 3285);
PAINT MONO (-3160 3285);
FORCEPROP 0 LASTPIN (-3150 3225) $PN BY1
J 2
(-3160 3235);
DISPLAY 0.680851 (-3160 3235);
PAINT MONO (-3160 3235);
FORCEPROP 0 LASTPIN (-3150 3175) $PN BY35
J 2
(-3160 3185);
DISPLAY 0.680851 (-3160 3185);
PAINT MONO (-3160 3185);
FORCEPROP 0 LASTPIN (-3150 3125) $PN CE13
J 2
(-3160 3135);
DISPLAY 0.680851 (-3160 3135);
PAINT MONO (-3160 3135);
FORCEPROP 0 LASTPIN (-3150 3075) $PN CE22
J 2
(-3160 3085);
DISPLAY 0.680851 (-3160 3085);
PAINT MONO (-3160 3085);
FORCEPROP 0 LASTPIN (-3150 3025) $PN CE32
J 2
(-3160 3035);
DISPLAY 0.680851 (-3160 3035);
PAINT MONO (-3160 3035);
FORCEPROP 0 LASTPIN (-3150 2975) $PN CE4
J 2
(-3160 2985);
DISPLAY 0.680851 (-3160 2985);
PAINT MONO (-3160 2985);
FORCEPROP 0 LASTPIN (-3150 2925) $PN CF2
J 2
(-3160 2935);
DISPLAY 0.680851 (-3160 2935);
PAINT MONO (-3160 2935);
FORCEPROP 0 LASTPIN (-3150 2875) $PN CF34
J 2
(-3160 2885);
DISPLAY 0.680851 (-3160 2885);
PAINT MONO (-3160 2885);
FORCEPROP 0 LASTPIN (-3150 2825) $PN CG1
J 2
(-3160 2835);
DISPLAY 0.680851 (-3160 2835);
PAINT MONO (-3160 2835);
FORCEPROP 0 LASTPIN (-3150 2775) $PN CG35
J 2
(-3160 2785);
DISPLAY 0.680851 (-3160 2785);
PAINT MONO (-3160 2785);
FORCEPROP 0 LASTPIN (-3150 2725) $PN CM13
J 2
(-3160 2735);
DISPLAY 0.680851 (-3160 2735);
PAINT MONO (-3160 2735);
FORCEPROP 0 LASTPIN (-3150 2675) $PN CM22
J 2
(-3160 2685);
DISPLAY 0.680851 (-3160 2685);
PAINT MONO (-3160 2685);
FORCEPROP 0 LASTPIN (-3150 2625) $PN CM32
J 2
(-3160 2635);
DISPLAY 0.680851 (-3160 2635);
PAINT MONO (-3160 2635);
FORCEPROP 0 LASTPIN (-3150 2575) $PN CM4
J 2
(-3160 2585);
DISPLAY 0.680851 (-3160 2585);
PAINT MONO (-3160 2585);
FORCEPROP 0 LASTPIN (-3150 2525) $PN CN2
J 2
(-3160 2535);
DISPLAY 0.680851 (-3160 2535);
PAINT MONO (-3160 2535);
FORCEPROP 0 LASTPIN (-3150 2475) $PN CN34
J 2
(-3160 2485);
DISPLAY 0.680851 (-3160 2485);
PAINT MONO (-3160 2485);
FORCEPROP 0 LASTPIN (-3150 2425) $PN CP1
J 2
(-3160 2435);
DISPLAY 0.680851 (-3160 2435);
PAINT MONO (-3160 2435);
FORCEPROP 0 LASTPIN (-3150 2375) $PN CP35
J 2
(-3160 2385);
DISPLAY 0.680851 (-3160 2385);
PAINT MONO (-3160 2385);
FORCEPROP 0 LASTPIN (-3150 2325) $PN CW13
J 2
(-3160 2335);
DISPLAY 0.680851 (-3160 2335);
PAINT MONO (-3160 2335);
FORCEPROP 0 LASTPIN (-3150 2275) $PN CW22
J 2
(-3160 2285);
DISPLAY 0.680851 (-3160 2285);
PAINT MONO (-3160 2285);
FORCEPROP 0 LASTPIN (-3150 2225) $PN CW32
J 2
(-3160 2235);
DISPLAY 0.680851 (-3160 2235);
PAINT MONO (-3160 2235);
FORCEPROP 0 LASTPIN (-3150 2175) $PN CW4
J 2
(-3160 2185);
DISPLAY 0.680851 (-3160 2185);
PAINT MONO (-3160 2185);
FORCEPROP 0 LASTPIN (-3150 2125) $PN CY2
J 2
(-3160 2135);
DISPLAY 0.680851 (-3160 2135);
PAINT MONO (-3160 2135);
FORCEPROP 0 LASTPIN (-3150 2075) $PN CY34
J 2
(-3160 2085);
DISPLAY 0.680851 (-3160 2085);
PAINT MONO (-3160 2085);
FORCEPROP 0 LASTPIN (-3150 2025) $PN DA1
J 2
(-3160 2035);
DISPLAY 0.680851 (-3160 2035);
PAINT MONO (-3160 2035);
FORCEPROP 0 LASTPIN (-3150 1975) $PN DA35
J 2
(-3160 1985);
DISPLAY 0.680851 (-3160 1985);
PAINT MONO (-3160 1985);
FORCEPROP 0 LASTPIN (-3150 1925) $PN DF13
J 2
(-3160 1935);
DISPLAY 0.680851 (-3160 1935);
PAINT MONO (-3160 1935);
FORCEPROP 0 LASTPIN (-3150 1875) $PN DF22
J 2
(-3160 1885);
DISPLAY 0.680851 (-3160 1885);
PAINT MONO (-3160 1885);
FORCEPROP 0 LASTPIN (-3150 1825) $PN DF32
J 2
(-3160 1835);
DISPLAY 0.680851 (-3160 1835);
PAINT MONO (-3160 1835);
FORCEPROP 0 LASTPIN (-3150 1775) $PN DF4
J 2
(-3160 1785);
DISPLAY 0.680851 (-3160 1785);
PAINT MONO (-3160 1785);
FORCEPROP 0 LASTPIN (-3150 1725) $PN DG2
J 2
(-3160 1735);
DISPLAY 0.680851 (-3160 1735);
PAINT MONO (-3160 1735);
FORCEPROP 0 LASTPIN (-3150 1675) $PN DG34
J 2
(-3160 1685);
DISPLAY 0.680851 (-3160 1685);
PAINT MONO (-3160 1685);
FORCEPROP 0 LASTPIN (-3150 1625) $PN DH1
J 2
(-3160 1635);
DISPLAY 0.680851 (-3160 1635);
PAINT MONO (-3160 1635);
FORCEPROP 0 LASTPIN (-3150 1575) $PN DH35
J 2
(-3160 1585);
DISPLAY 0.680851 (-3160 1585);
PAINT MONO (-3160 1585);
FORCEPROP 0 LASTPIN (-3150 1525) $PN DN13
J 2
(-3160 1535);
DISPLAY 0.680851 (-3160 1535);
PAINT MONO (-3160 1535);
FORCEPROP 0 LASTPIN (-2200 5575) $PN DN22
J 0
(-2190 5585);
DISPLAY 0.680851 (-2190 5585);
PAINT MONO (-2190 5585);
FORCEPROP 0 LASTPIN (-2200 5525) $PN DN32
J 0
(-2190 5535);
DISPLAY 0.680851 (-2190 5535);
PAINT MONO (-2190 5535);
FORCEPROP 0 LASTPIN (-2200 5475) $PN DN4
J 0
(-2190 5485);
DISPLAY 0.680851 (-2190 5485);
PAINT MONO (-2190 5485);
FORCEPROP 0 LASTPIN (-2200 5425) $PN DP2
J 0
(-2190 5435);
DISPLAY 0.680851 (-2190 5435);
PAINT MONO (-2190 5435);
FORCEPROP 0 LASTPIN (-2200 5375) $PN DP34
J 0
(-2190 5385);
DISPLAY 0.680851 (-2190 5385);
PAINT MONO (-2190 5385);
FORCEPROP 0 LASTPIN (-2200 5325) $PN DR1
J 0
(-2190 5335);
DISPLAY 0.680851 (-2190 5335);
PAINT MONO (-2190 5335);
FORCEPROP 0 LASTPIN (-2200 5275) $PN DR35
J 0
(-2190 5285);
DISPLAY 0.680851 (-2190 5285);
PAINT MONO (-2190 5285);
FORCEPROP 0 LASTPIN (-2200 5225) $PN DY13
J 0
(-2190 5235);
DISPLAY 0.680851 (-2190 5235);
PAINT MONO (-2190 5235);
FORCEPROP 0 LASTPIN (-2200 5175) $PN DY22
J 0
(-2190 5185);
DISPLAY 0.680851 (-2190 5185);
PAINT MONO (-2190 5185);
FORCEPROP 0 LASTPIN (-2200 5125) $PN DY32
J 0
(-2190 5135);
DISPLAY 0.680851 (-2190 5135);
PAINT MONO (-2190 5135);
FORCEPROP 0 LASTPIN (-2200 5075) $PN DY4
J 0
(-2190 5085);
DISPLAY 0.680851 (-2190 5085);
PAINT MONO (-2190 5085);
FORCEPROP 0 LASTPIN (-2200 5025) $PN E14
J 0
(-2190 5035);
DISPLAY 0.680851 (-2190 5035);
PAINT MONO (-2190 5035);
FORCEPROP 0 LASTPIN (-2200 4975) $PN E27
J 0
(-2190 4985);
DISPLAY 0.680851 (-2190 4985);
PAINT MONO (-2190 4985);
FORCEPROP 0 LASTPIN (-2200 4925) $PN E33
J 0
(-2190 4935);
DISPLAY 0.680851 (-2190 4935);
PAINT MONO (-2190 4935);
FORCEPROP 0 LASTPIN (-2200 4875) $PN EA2
J 0
(-2190 4885);
DISPLAY 0.680851 (-2190 4885);
PAINT MONO (-2190 4885);
FORCEPROP 0 LASTPIN (-2200 4825) $PN EA34
J 0
(-2190 4835);
DISPLAY 0.680851 (-2190 4835);
PAINT MONO (-2190 4835);
FORCEPROP 0 LASTPIN (-2200 4775) $PN EB1
J 0
(-2190 4785);
DISPLAY 0.680851 (-2190 4785);
PAINT MONO (-2190 4785);
FORCEPROP 0 LASTPIN (-2200 4725) $PN EB35
J 0
(-2190 4735);
DISPLAY 0.680851 (-2190 4735);
PAINT MONO (-2190 4735);
FORCEPROP 0 LASTPIN (-2200 4675) $PN EG13
J 0
(-2190 4685);
DISPLAY 0.680851 (-2190 4685);
PAINT MONO (-2190 4685);
FORCEPROP 0 LASTPIN (-2200 4625) $PN EG22
J 0
(-2190 4635);
DISPLAY 0.680851 (-2190 4635);
PAINT MONO (-2190 4635);
FORCEPROP 0 LASTPIN (-2200 4575) $PN EG32
J 0
(-2190 4585);
DISPLAY 0.680851 (-2190 4585);
PAINT MONO (-2190 4585);
FORCEPROP 0 LASTPIN (-2200 4525) $PN EG4
J 0
(-2190 4535);
DISPLAY 0.680851 (-2190 4535);
PAINT MONO (-2190 4535);
FORCEPROP 0 LASTPIN (-2200 4475) $PN EH2
J 0
(-2190 4485);
DISPLAY 0.680851 (-2190 4485);
PAINT MONO (-2190 4485);
FORCEPROP 0 LASTPIN (-2200 4425) $PN EH34
J 0
(-2190 4435);
DISPLAY 0.680851 (-2190 4435);
PAINT MONO (-2190 4435);
FORCEPROP 0 LASTPIN (-2200 4375) $PN EJ1
J 0
(-2190 4385);
DISPLAY 0.680851 (-2190 4385);
PAINT MONO (-2190 4385);
FORCEPROP 0 LASTPIN (-2200 4325) $PN EJ35
J 0
(-2190 4335);
DISPLAY 0.680851 (-2190 4335);
PAINT MONO (-2190 4335);
FORCEPROP 0 LASTPIN (-2200 4275) $PN EP13
J 0
(-2190 4285);
DISPLAY 0.680851 (-2190 4285);
PAINT MONO (-2190 4285);
FORCEPROP 0 LASTPIN (-2200 4225) $PN EP22
J 0
(-2190 4235);
DISPLAY 0.680851 (-2190 4235);
PAINT MONO (-2190 4235);
FORCEPROP 0 LASTPIN (-2200 4175) $PN EP32
J 0
(-2190 4185);
DISPLAY 0.680851 (-2190 4185);
PAINT MONO (-2190 4185);
FORCEPROP 0 LASTPIN (-2200 4125) $PN EP4
J 0
(-2190 4135);
DISPLAY 0.680851 (-2190 4135);
PAINT MONO (-2190 4135);
FORCEPROP 0 LASTPIN (-2200 4075) $PN ER2
J 0
(-2190 4085);
DISPLAY 0.680851 (-2190 4085);
PAINT MONO (-2190 4085);
FORCEPROP 0 LASTPIN (-2200 4025) $PN ER34
J 0
(-2190 4035);
DISPLAY 0.680851 (-2190 4035);
PAINT MONO (-2190 4035);
FORCEPROP 0 LASTPIN (-2200 3975) $PN ET1
J 0
(-2190 3985);
DISPLAY 0.680851 (-2190 3985);
PAINT MONO (-2190 3985);
FORCEPROP 0 LASTPIN (-2200 3925) $PN ET35
J 0
(-2190 3935);
DISPLAY 0.680851 (-2190 3935);
PAINT MONO (-2190 3935);
FORCEPROP 0 LASTPIN (-2200 3875) $PN FA15
J 0
(-2190 3885);
DISPLAY 0.680851 (-2190 3885);
PAINT MONO (-2190 3885);
FORCEPROP 0 LASTPIN (-2200 3825) $PN FA32
J 0
(-2190 3835);
DISPLAY 0.680851 (-2190 3835);
PAINT MONO (-2190 3835);
FORCEPROP 0 LASTPIN (-2200 3775) $PN FB2
J 0
(-2190 3785);
DISPLAY 0.680851 (-2190 3785);
PAINT MONO (-2190 3785);
FORCEPROP 0 LASTPIN (-2200 3725) $PN FB34
J 0
(-2190 3735);
DISPLAY 0.680851 (-2190 3735);
PAINT MONO (-2190 3735);
FORCEPROP 0 LASTPIN (-2200 3675) $PN FC19
J 0
(-2190 3685);
DISPLAY 0.680851 (-2190 3685);
PAINT MONO (-2190 3685);
FORCEPROP 0 LASTPIN (-2200 3625) $PN FC23
J 0
(-2190 3635);
DISPLAY 0.680851 (-2190 3635);
PAINT MONO (-2190 3635);
FORCEPROP 0 LASTPIN (-2200 3575) $PN FC25
J 0
(-2190 3585);
DISPLAY 0.680851 (-2190 3585);
PAINT MONO (-2190 3585);
FORCEPROP 0 LASTPIN (-2200 3525) $PN FC28
J 0
(-2190 3535);
DISPLAY 0.680851 (-2190 3535);
PAINT MONO (-2190 3535);
FORCEPROP 0 LASTPIN (-2200 3475) $PN FC3
J 0
(-2190 3485);
DISPLAY 0.680851 (-2190 3485);
PAINT MONO (-2190 3485);
FORCEPROP 0 LASTPIN (-2200 3425) $PN FC6
J 0
(-2190 3435);
DISPLAY 0.680851 (-2190 3435);
PAINT MONO (-2190 3435);
FORCEPROP 0 LASTPIN (-2200 3375) $PN FC9
J 0
(-2190 3385);
DISPLAY 0.680851 (-2190 3385);
PAINT MONO (-2190 3385);
FORCEPROP 0 LASTPIN (-2200 3325) $PN FD1
J 0
(-2190 3335);
DISPLAY 0.680851 (-2190 3335);
PAINT MONO (-2190 3335);
FORCEPROP 0 LASTPIN (-2200 3275) $PN FD35
J 0
(-2190 3285);
DISPLAY 0.680851 (-2190 3285);
PAINT MONO (-2190 3285);
FORCEPROP 0 LASTPIN (-2200 3225) $PN FF14
J 0
(-2190 3235);
DISPLAY 0.680851 (-2190 3235);
PAINT MONO (-2190 3235);
FORCEPROP 0 LASTPIN (-2200 3175) $PN FF21
J 0
(-2190 3185);
DISPLAY 0.680851 (-2190 3185);
PAINT MONO (-2190 3185);
FORCEPROP 0 LASTPIN (-2200 3125) $PN FJ12
J 0
(-2190 3135);
DISPLAY 0.680851 (-2190 3135);
PAINT MONO (-2190 3135);
FORCEPROP 0 LASTPIN (-2200 3075) $PN FJ19
J 0
(-2190 3085);
DISPLAY 0.680851 (-2190 3085);
PAINT MONO (-2190 3085);
FORCEPROP 0 LASTPIN (-2200 3025) $PN H12
J 0
(-2190 3035);
DISPLAY 0.680851 (-2190 3035);
PAINT MONO (-2190 3035);
FORCEPROP 0 LASTPIN (-2200 2975) $PN H16
J 0
(-2190 2985);
DISPLAY 0.680851 (-2190 2985);
PAINT MONO (-2190 2985);
FORCEPROP 0 LASTPIN (-2200 2925) $PN H19
J 0
(-2190 2935);
DISPLAY 0.680851 (-2190 2935);
PAINT MONO (-2190 2935);
FORCEPROP 0 LASTPIN (-2200 2875) $PN H31
J 0
(-2190 2885);
DISPLAY 0.680851 (-2190 2885);
PAINT MONO (-2190 2885);
FORCEPROP 0 LASTPIN (-2200 2825) $PN J22
J 0
(-2190 2835);
DISPLAY 0.680851 (-2190 2835);
PAINT MONO (-2190 2835);
FORCEPROP 0 LASTPIN (-2200 2775) $PN J4
J 0
(-2190 2785);
DISPLAY 0.680851 (-2190 2785);
PAINT MONO (-2190 2785);
FORCEPROP 0 LASTPIN (-2200 2725) $PN K2
J 0
(-2190 2735);
DISPLAY 0.680851 (-2190 2735);
PAINT MONO (-2190 2735);
FORCEPROP 0 LASTPIN (-2200 2675) $PN K34
J 0
(-2190 2685);
DISPLAY 0.680851 (-2190 2685);
PAINT MONO (-2190 2685);
FORCEPROP 0 LASTPIN (-2200 2625) $PN L1
J 0
(-2190 2635);
DISPLAY 0.680851 (-2190 2635);
PAINT MONO (-2190 2635);
FORCEPROP 0 LASTPIN (-2200 2575) $PN L35
J 0
(-2190 2585);
DISPLAY 0.680851 (-2190 2585);
PAINT MONO (-2190 2585);
FORCEPROP 0 LASTPIN (-2200 2525) $PN T13
J 0
(-2190 2535);
DISPLAY 0.680851 (-2190 2535);
PAINT MONO (-2190 2535);
FORCEPROP 0 LASTPIN (-2200 2475) $PN T22
J 0
(-2190 2485);
DISPLAY 0.680851 (-2190 2485);
PAINT MONO (-2190 2485);
FORCEPROP 0 LASTPIN (-2200 2425) $PN T32
J 0
(-2190 2435);
DISPLAY 0.680851 (-2190 2435);
PAINT MONO (-2190 2435);
FORCEPROP 0 LASTPIN (-2200 2375) $PN T4
J 0
(-2190 2385);
DISPLAY 0.680851 (-2190 2385);
PAINT MONO (-2190 2385);
FORCEPROP 0 LASTPIN (-2200 2325) $PN U2
J 0
(-2190 2335);
DISPLAY 0.680851 (-2190 2335);
PAINT MONO (-2190 2335);
FORCEPROP 0 LASTPIN (-2200 2275) $PN U34
J 0
(-2190 2285);
DISPLAY 0.680851 (-2190 2285);
PAINT MONO (-2190 2285);
FORCEPROP 0 LASTPIN (-2200 2225) $PN V1
J 0
(-2190 2235);
DISPLAY 0.680851 (-2190 2235);
PAINT MONO (-2190 2235);
FORCEPROP 0 LASTPIN (-2200 2175) $PN V35
J 0
(-2190 2185);
DISPLAY 0.680851 (-2190 2185);
PAINT MONO (-2190 2185);
FORCEPROP 0 LASTPIN (-2200 2075) $PN A1
J 0
(-2190 2085);
DISPLAY 0.680851 (-2190 2085);
PAINT MONO (-2190 2085);
FORCEPROP 0 LASTPIN (-2200 2025) $PN A35
J 0
(-2190 2035);
DISPLAY 0.680851 (-2190 2035);
PAINT MONO (-2190 2035);
FORCEPROP 0 LASTPIN (-2200 1975) $PN C2
J 0
(-2190 1985);
DISPLAY 0.680851 (-2190 1985);
PAINT MONO (-2190 1985);
FORCEPROP 0 LASTPIN (-2200 1925) $PN C34
J 0
(-2190 1935);
DISPLAY 0.680851 (-2190 1935);
PAINT MONO (-2190 1935);
FORCEPROP 0 LASTPIN (-2200 1875) $PN D1
J 0
(-2190 1885);
DISPLAY 0.680851 (-2190 1885);
PAINT MONO (-2190 1885);
FORCEPROP 0 LASTPIN (-2200 1825) $PN D35
J 0
(-2190 1835);
DISPLAY 0.680851 (-2190 1835);
PAINT MONO (-2190 1835);
FORCEPROP 0 LASTPIN (-2200 1775) $PN FE2
J 0
(-2190 1785);
DISPLAY 0.680851 (-2190 1785);
PAINT MONO (-2190 1785);
FORCEPROP 0 LASTPIN (-2200 1725) $PN FE34
J 0
(-2190 1735);
DISPLAY 0.680851 (-2190 1735);
PAINT MONO (-2190 1735);
FORCEPROP 0 LASTPIN (-2200 1675) $PN FG1
J 0
(-2190 1685);
DISPLAY 0.680851 (-2190 1685);
PAINT MONO (-2190 1685);
FORCEPROP 0 LASTPIN (-2200 1625) $PN FG35
J 0
(-2190 1635);
DISPLAY 0.680851 (-2190 1635);
PAINT MONO (-2190 1635);
FORCEPROP 0 LASTPIN (-2200 1575) $PN FH2
J 0
(-2190 1585);
DISPLAY 0.680851 (-2190 1585);
PAINT MONO (-2190 1585);
FORCEPROP 0 LASTPIN (-2200 1525) $PN FH34
J 0
(-2190 1535);
DISPLAY 0.680851 (-2190 1535);
PAINT MONO (-2190 1535);
FORCEPROP 2 LAST PART_TYPE SMLF
J 0
(-3000 6000);
DISPLAY 0.680851 (-3000 6000);
FORCEPROP 1 LAST MATERIAL IC
J 0
(-3000 5750);
DISPLAY 0.723404 (-3000 5750);
PAINT GREEN (-3000 5750);
FORCEPROP 2 LAST VALUE PT5161LRS
J 0
(-3000 5950);
DISPLAY 0.680851 (-3000 5950);
FORCEPROP 1 LAST NEEDS_NO_SIZE TRUE
J 0
(-2650 3575);
DISPLAY 0.723404 (-2650 3575);
PAINT GREEN (-2650 3575);
DISPLAY INVISIBLE (-2650 3575);
FORCEPROP 1 LAST CDS_LMAN_SYM_OUTLINE -350,2150,300,-2150
J 0
(-2650 3575);
DISPLAY 0.468085 (-2650 3575);
PAINT GREEN (-2650 3575);
DISPLAY INVISIBLE (-2650 3575);
FORCEPROP 2 LAST CDS_LIB pure_quanta
J 0
(-2650 3575);
DISPLAY INVISIBLE (-2650 3575);
FORCEPROP 1 LAST PATH I17
J 0
(-2650 3575);
DISPLAY 0.723404 (-2650 3575);
PAINT GREEN (-2650 3575);
DISPLAY INVISIBLE (-2650 3575);
FORCEPROP 1 LAST PART_NUMBER AJ051610U03
J 0
(-3000 5825);
DISPLAY 0.723404 (-3000 5825);
PAINT GREEN (-3000 5825);
DISPLAY INVISIBLE (-3000 5825);
FORCEADD Q_RES..2
(-7875 3350);
FORCEPROP 1 LAST LOCATION R1041
J 0
(-7830 3475);
DISPLAY 0.978723 (-7830 3475);
PAINT WHITE (-7830 3475);
FORCEPROP 0 LAST $SEC 1
J 0
(-7825 3525);
DISPLAY 0.680851 (-7825 3525);
PAINT MONO (-7825 3525);
DISPLAY INVISIBLE (-7825 3525);
FORCEPROP 0 LAST CDS_SEC 1
J 0
(-7825 3525);
DISPLAY 0.680851 (-7825 3525);
DISPLAY INVISIBLE (-7825 3525);
FORCEPROP 1 LASTPIN (-7875 3450) $PN 1
J 0
(-7870 3412);
DISPLAY 0.787234 (-7870 3412);
PAINT MONO (-7870 3412);
FORCEPROP 1 LASTPIN (-7875 3250) $PN 2
J 0
(-7870 3260);
DISPLAY 0.787234 (-7870 3260);
PAINT MONO (-7870 3260);
FORCEPROP 1 LAST PACK_TYPE 0201LF
J 0
(-7835 3175);
DISPLAY 0.978723 (-7835 3175);
FORCEPROP 1 LAST VALUE 200
J 0
(-7830 3425);
DISPLAY 0.978723 (-7830 3425);
FORCEPROP 1 LAST TOLERANCE 1%
J 0
(-7830 3375);
DISPLAY 0.978723 (-7830 3375);
FORCEPROP 1 LAST WATTAGE 1/20W
J 0
(-7835 3325);
DISPLAY 0.978723 (-7835 3325);
FORCEPROP 1 LAST MATERIAL CHIP
J 0
(-7835 3275);
DISPLAY 0.978723 (-7835 3275);
FORCEPROP 2 LAST CDS_LIB pure_quanta
J 0
(-7875 3350);
DISPLAY INVISIBLE (-7875 3350);
FORCEPROP 1 LAST PATH I18
J 0
(-7825 3525);
DISPLAY 0.978723 (-7825 3525);
PAINT WHITE (-7825 3525);
DISPLAY INVISIBLE (-7825 3525);
FORCEPROP 1 LAST PART_NUMBER CS12001FE12
J 0
(-7835 3225);
DISPLAY 0.978723 (-7835 3225);
DISPLAY INVISIBLE (-7835 3225);
FORCEADD Q_RES..2
(-8900 3900);
FORCEPROP 1 LAST LOCATION R1040
J 0
(-8855 4025);
DISPLAY 0.787234 (-8855 4025);
PAINT SKYBLUE (-8855 4025);
FORCEPROP 0 LAST $SEC 1
J 0
(-8850 4075);
DISPLAY 0.680851 (-8850 4075);
PAINT MONO (-8850 4075);
DISPLAY INVISIBLE (-8850 4075);
FORCEPROP 0 LAST CDS_SEC 1
J 0
(-8850 4075);
DISPLAY 0.680851 (-8850 4075);
DISPLAY INVISIBLE (-8850 4075);
FORCEPROP 1 LASTPIN (-8900 4000) $PN 1
J 0
(-8895 3962);
DISPLAY 0.787234 (-8895 3962);
PAINT MONO (-8895 3962);
FORCEPROP 1 LASTPIN (-8900 3800) $PN 2
J 0
(-8895 3810);
DISPLAY 0.787234 (-8895 3810);
PAINT MONO (-8895 3810);
FORCEPROP 1 LAST MATERIAL EMPTY
J 0
(-8860 3825);
DISPLAY 0.787234 (-8860 3825);
PAINT RED (-8860 3825);
FORCEPROP 1 LAST VALUE 1K
J 0
(-8855 3975);
DISPLAY 0.787234 (-8855 3975);
FORCEPROP 1 LAST TOLERANCE 1%
J 0
(-8855 3925);
DISPLAY 0.787234 (-8855 3925);
FORCEPROP 1 LAST PACK_TYPE 0201LF
J 0
(-8860 3725);
DISPLAY 0.787234 (-8860 3725);
FORCEPROP 1 LAST WATTAGE 1/20W
J 0
(-8860 3875);
DISPLAY 0.787234 (-8860 3875);
FORCEPROP 2 LAST CDS_LIB pure_quanta
J 0
(-8900 3900);
DISPLAY INVISIBLE (-8900 3900);
FORCEPROP 1 LAST PATH I19
J 0
(-8850 4075);
DISPLAY 0.978723 (-8850 4075);
PAINT WHITE (-8850 4075);
DISPLAY INVISIBLE (-8850 4075);
FORCEPROP 1 LAST PART_NUMBER CS21001FE07
J 0
(-8860 3775);
DISPLAY 0.978723 (-8860 3775);
DISPLAY INVISIBLE (-8860 3775);
FORCEADD P1V0..1
(-8900 4125);
FORCEPROP 3 LASTPIN (-8900 4075) SIG_NAME P1V8_CPU0_RT_1D\g
J 0
(-8890 4085);
DISPLAY 0.659574 (-8890 4085);
PAINT MONO (-8890 4085);
DISPLAY INVISIBLE (-8890 4085);
FORCEPROP 1 LAST HDL_POWER P1V8_CPU0_RT_1D
J 1
(-8900 4175);
DISPLAY 0.489362 (-8900 4175);
PAINT SKYBLUE (-8900 4175);
FORCEPROP 2 LAST CDS_LIB pure_quanta_power
J 0
(-8900 4125);
DISPLAY INVISIBLE (-8900 4125);
FORCEPROP 1 LAST PATH I2
J 0
(-8850 4150);
DISPLAY 0.872340 (-8850 4150);
PAINT AQUA (-8850 4150);
DISPLAY INVISIBLE (-8850 4150);
FORCEADD UNIVERSAL_GND..1
(-7875 3100);
FORCEPROP 3 LASTPIN (-7875 3150) SIG_NAME GND\g
J 0
(-7865 3160);
DISPLAY 0.659574 (-7865 3160);
PAINT MONO (-7865 3160);
DISPLAY INVISIBLE (-7865 3160);
FORCEPROP 2 LAST CDS_LIB pure_quanta_power
J 0
(-7875 3100);
DISPLAY INVISIBLE (-7875 3100);
FORCEPROP 1 LAST HDL_POWER GND
J 1
(-7850 3025);
DISPLAY 0.872340 (-7850 3025);
PAINT GREEN (-7850 3025);
DISPLAY INVISIBLE (-7850 3025);
FORCEPROP 1 LAST PATH I3
J 0
(-7800 3100);
DISPLAY 0.872340 (-7800 3100);
PAINT AQUA (-7800 3100);
DISPLAY INVISIBLE (-7800 3100);
FORCEADD PT5161LRS..4
(-6725 4150);
FORCEPROP 1 LAST LOCATION U6011
J 0
(-7175 5075);
DISPLAY 0.723404 (-7175 5075);
PAINT SKYBLUE (-7175 5075);
FORCEPROP 0 LAST $SEC 4
J 0
(-7175 5225);
DISPLAY 0.680851 (-7175 5225);
PAINT MONO (-7175 5225);
DISPLAY INVISIBLE (-7175 5225);
FORCEPROP 0 LAST CDS_SEC 4
J 0
(-7175 5225);
DISPLAY 0.680851 (-7175 5225);
DISPLAY INVISIBLE (-7175 5225);
FORCEPROP 0 LASTPIN (-7325 4750) $PN BV20
J 2
(-7335 4760);
DISPLAY 0.680851 (-7335 4760);
PAINT MONO (-7335 4760);
FORCEPROP 0 LASTPIN (-7325 4700) $PN CE17
J 2
(-7335 4710);
DISPLAY 0.680851 (-7335 4710);
PAINT MONO (-7335 4710);
FORCEPROP 0 LASTPIN (-7325 4650) $PN CE20
J 2
(-7335 4660);
DISPLAY 0.680851 (-7335 4660);
PAINT MONO (-7335 4660);
FORCEPROP 0 LASTPIN (-7325 4600) $PN CM17
J 2
(-7335 4610);
DISPLAY 0.680851 (-7335 4610);
PAINT MONO (-7335 4610);
FORCEPROP 0 LASTPIN (-7325 4550) $PN CM20
J 2
(-7335 4560);
DISPLAY 0.680851 (-7335 4560);
PAINT MONO (-7335 4560);
FORCEPROP 0 LASTPIN (-7325 4100) $PN BV17
J 2
(-7335 4110);
DISPLAY 0.680851 (-7335 4110);
PAINT MONO (-7335 4110);
FORCEPROP 0 LASTPIN (-6175 4750) $PN AC17
J 0
(-6165 4760);
DISPLAY 0.680851 (-6165 4760);
PAINT MONO (-6165 4760);
FORCEPROP 0 LASTPIN (-6175 4700) $PN AC20
J 0
(-6165 4710);
DISPLAY 0.680851 (-6165 4710);
PAINT MONO (-6165 4710);
FORCEPROP 0 LASTPIN (-6175 4650) $PN AK17
J 0
(-6165 4660);
DISPLAY 0.680851 (-6165 4660);
PAINT MONO (-6165 4660);
FORCEPROP 0 LASTPIN (-6175 4600) $PN AK20
J 0
(-6165 4610);
DISPLAY 0.680851 (-6165 4610);
PAINT MONO (-6165 4610);
FORCEPROP 0 LASTPIN (-6175 4550) $PN AU17
J 0
(-6165 4560);
DISPLAY 0.680851 (-6165 4560);
PAINT MONO (-6165 4560);
FORCEPROP 0 LASTPIN (-6175 4500) $PN AU20
J 0
(-6165 4510);
DISPLAY 0.680851 (-6165 4510);
PAINT MONO (-6165 4510);
FORCEPROP 0 LASTPIN (-6175 4450) $PN BD17
J 0
(-6165 4460);
DISPLAY 0.680851 (-6165 4460);
PAINT MONO (-6165 4460);
FORCEPROP 0 LASTPIN (-6175 4400) $PN BD20
J 0
(-6165 4410);
DISPLAY 0.680851 (-6165 4410);
PAINT MONO (-6165 4410);
FORCEPROP 0 LASTPIN (-6175 4350) $PN DF17
J 0
(-6165 4360);
DISPLAY 0.680851 (-6165 4360);
PAINT MONO (-6165 4360);
FORCEPROP 0 LASTPIN (-6175 4300) $PN DF20
J 0
(-6165 4310);
DISPLAY 0.680851 (-6165 4310);
PAINT MONO (-6165 4310);
FORCEPROP 0 LASTPIN (-6175 4250) $PN DN17
J 0
(-6165 4260);
DISPLAY 0.680851 (-6165 4260);
PAINT MONO (-6165 4260);
FORCEPROP 0 LASTPIN (-6175 4200) $PN DN20
J 0
(-6165 4210);
DISPLAY 0.680851 (-6165 4210);
PAINT MONO (-6165 4210);
FORCEPROP 0 LASTPIN (-6175 4150) $PN DY17
J 0
(-6165 4160);
DISPLAY 0.680851 (-6165 4160);
PAINT MONO (-6165 4160);
FORCEPROP 0 LASTPIN (-6175 4100) $PN DY20
J 0
(-6165 4110);
DISPLAY 0.680851 (-6165 4110);
PAINT MONO (-6165 4110);
FORCEPROP 0 LASTPIN (-6175 4050) $PN EG17
J 0
(-6165 4060);
DISPLAY 0.680851 (-6165 4060);
PAINT MONO (-6165 4060);
FORCEPROP 0 LASTPIN (-6175 4000) $PN EG20
J 0
(-6165 4010);
DISPLAY 0.680851 (-6165 4010);
PAINT MONO (-6165 4010);
FORCEPROP 0 LASTPIN (-6175 3950) $PN EP17
J 0
(-6165 3960);
DISPLAY 0.680851 (-6165 3960);
PAINT MONO (-6165 3960);
FORCEPROP 0 LASTPIN (-6175 3900) $PN EP20
J 0
(-6165 3910);
DISPLAY 0.680851 (-6165 3910);
PAINT MONO (-6165 3910);
FORCEPROP 0 LASTPIN (-6175 3850) $PN T17
J 0
(-6165 3860);
DISPLAY 0.680851 (-6165 3860);
PAINT MONO (-6165 3860);
FORCEPROP 0 LASTPIN (-6175 3800) $PN T20
J 0
(-6165 3810);
DISPLAY 0.680851 (-6165 3810);
PAINT MONO (-6165 3810);
FORCEPROP 0 LASTPIN (-6175 3650) $PN BL17
J 0
(-6165 3660);
DISPLAY 0.680851 (-6165 3660);
PAINT MONO (-6165 3660);
FORCEPROP 0 LASTPIN (-6175 3600) $PN BL20
J 0
(-6165 3610);
DISPLAY 0.680851 (-6165 3610);
PAINT MONO (-6165 3610);
FORCEPROP 0 LASTPIN (-6175 3550) $PN CW17
J 0
(-6165 3560);
DISPLAY 0.680851 (-6165 3560);
PAINT MONO (-6165 3560);
FORCEPROP 0 LASTPIN (-6175 3500) $PN CW20
J 0
(-6165 3510);
DISPLAY 0.680851 (-6165 3510);
PAINT MONO (-6165 3510);
FORCEPROP 0 LASTPIN (-7325 3650) $PN G1
J 2
(-7335 3660);
DISPLAY 0.680851 (-7335 3660);
PAINT MONO (-7335 3660);
FORCEPROP 2 LAST VALUE PT5161LRS
J 0
(-7175 5125);
DISPLAY 0.680851 (-7175 5125);
FORCEPROP 2 LAST PART_TYPE SMLF
J 0
(-7175 5175);
DISPLAY 0.680851 (-7175 5175);
FORCEPROP 1 LAST MATERIAL IC
J 0
(-7175 4925);
DISPLAY 0.723404 (-7175 4925);
PAINT GREEN (-7175 4925);
FORCEPROP 1 LAST NEEDS_NO_SIZE TRUE
J 0
(-6725 4150);
DISPLAY 0.723404 (-6725 4150);
PAINT GREEN (-6725 4150);
DISPLAY INVISIBLE (-6725 4150);
FORCEPROP 1 LAST CDS_LMAN_SYM_OUTLINE -450,750,400,-750
J 0
(-6725 4150);
DISPLAY 0.468085 (-6725 4150);
PAINT GREEN (-6725 4150);
DISPLAY INVISIBLE (-6725 4150);
FORCEPROP 2 LAST CDS_LIB pure_quanta
J 0
(-6725 4150);
DISPLAY INVISIBLE (-6725 4150);
FORCEPROP 1 LAST PATH I5
J 0
(-6725 4150);
DISPLAY 0.723404 (-6725 4150);
PAINT GREEN (-6725 4150);
DISPLAY INVISIBLE (-6725 4150);
FORCEPROP 1 LAST PART_NUMBER AJ051610U03
J 0
(-7175 5000);
DISPLAY 0.723404 (-7175 5000);
PAINT GREEN (-7175 5000);
DISPLAY INVISIBLE (-7175 5000);
FORCEADD P1V0..1
(-4875 3800);
FORCEPROP 3 LASTPIN (-4875 3750) SIG_NAME P0V9_CPU0_RT_2D\g
J 0
(-4865 3760);
DISPLAY 0.659574 (-4865 3760);
PAINT MONO (-4865 3760);
DISPLAY INVISIBLE (-4865 3760);
FORCEPROP 1 LAST HDL_POWER P0V9_CPU0_RT_2D
J 1
(-4875 3850);
DISPLAY 0.489362 (-4875 3850);
PAINT SKYBLUE (-4875 3850);
FORCEPROP 2 LAST CDS_LIB pure_quanta_power
J 0
(-4875 3800);
DISPLAY INVISIBLE (-4875 3800);
FORCEPROP 1 LAST PATH I6
J 0
(-4825 3825);
DISPLAY 0.872340 (-4825 3825);
PAINT AQUA (-4825 3825);
DISPLAY INVISIBLE (-4825 3825);
FORCEADD P1V0..1
(-8575 4400);
FORCEPROP 3 LASTPIN (-8575 4350) SIG_NAME P1V8_CPU0_RT1_1A_1D\g
J 0
(-8565 4360);
DISPLAY 0.659574 (-8565 4360);
PAINT MONO (-8565 4360);
DISPLAY INVISIBLE (-8565 4360);
FORCEPROP 1 LAST HDL_POWER P1V8_CPU0_RT1_1A_1D
J 1
(-8575 4450);
DISPLAY 0.489362 (-8575 4450);
PAINT SKYBLUE (-8575 4450);
FORCEPROP 2 LAST CDS_LIB pure_quanta_power
J 0
(-8575 4400);
DISPLAY INVISIBLE (-8575 4400);
FORCEPROP 1 LAST PATH I7
J 0
(-8525 4425);
DISPLAY 0.872340 (-8525 4425);
PAINT AQUA (-8525 4425);
DISPLAY INVISIBLE (-8525 4425);
FORCEADD P1V0..1
(-8000 4850);
FORCEPROP 3 LASTPIN (-8000 4800) SIG_NAME P1V8_CPU0_RT1_1A\g
J 0
(-7990 4810);
DISPLAY 0.659574 (-7990 4810);
PAINT MONO (-7990 4810);
DISPLAY INVISIBLE (-7990 4810);
FORCEPROP 1 LAST HDL_POWER P1V8_CPU0_RT1_1A
J 1
(-8000 4900);
DISPLAY 0.489362 (-8000 4900);
PAINT SKYBLUE (-8000 4900);
FORCEPROP 2 LAST CDS_LIB pure_quanta_power
J 0
(-8000 4850);
DISPLAY INVISIBLE (-8000 4850);
FORCEPROP 1 LAST PATH I8
J 0
(-7950 4875);
DISPLAY 0.872340 (-7950 4875);
PAINT AQUA (-7950 4875);
DISPLAY INVISIBLE (-7950 4875);
FORCEADD VCC_CORE..1
(-5475 4550);
FORCEPROP 3 LASTPIN (-5475 4500) SIG_NAME P0V9_CPU0_RT1_2A_2D\g
J 0
(-5465 4510);
DISPLAY 0.659574 (-5465 4510);
PAINT MONO (-5465 4510);
DISPLAY INVISIBLE (-5465 4510);
FORCEPROP 1 LAST HDL_POWER P0V9_CPU0_RT1_2A_2D
J 1
(-5475 4600);
DISPLAY 0.617021 (-5475 4600);
PAINT SKYBLUE (-5475 4600);
FORCEPROP 2 LAST CDS_LIB pure_quanta_power
J 0
(-5475 4550);
DISPLAY INVISIBLE (-5475 4550);
FORCEPROP 1 LAST PATH I9
J 0
(-5425 4575);
DISPLAY 0.872340 (-5425 4575);
PAINT AQUA (-5425 4575);
DISPLAY INVISIBLE (-5425 4575);
FORCEADD QUANTA_TITLE_BLOCK_C..1
(0 0);
FORCEPROP 0 LAST CDS_CON_LAST_MODIFIED Thu Sep 14 16:13:08 2023
J 0
(-1885 15);
DISPLAY INVISIBLE (-1885 15);
FORCEPROP 1 LAST CUSTOM_TXT_CDS <CON_LAST_MODIFIED>
J 0
(-1885 15);
DISPLAY 0.978723 (-1885 15);
FORCEPROP 2 LAST CUSTOM_TXT_CDS <XR_PAGE_TITLE>
J 0
(-7890 5250);
DISPLAY 0.638298 (-7890 5250);
PAINT PINK (-7890 5250);
DISPLAY INVISIBLE (-7890 5250);
FORCEPROP 1 LAST CUSTOM_TXT_CDS <NAME_2>
J 0
(-3175 50);
FORCEPROP 1 LAST CUSTOM_TXT_CDS <NAME_1>
J 0
(-3175 175);
FORCEPROP 1 LAST CUSTOM_TXT_CDS <Q_NUMBER>
J 0
(-1403 103);
DISPLAY 1.212766 (-1403 103);
FORCEPROP 1 LAST CUSTOM_TXT_CDS <Q_PROJ>
J 0
(-2382 102);
DISPLAY 1.212766 (-2382 102);
FORCEPROP 1 LAST CUSTOM_TXT_CDS <Q_REV>
J 0
(-184 103);
DISPLAY 1.212766 (-184 103);
FORCEPROP 1 LAST CUSTOM_TXT_CDS <CON_PAGE_NUM> OF <CON_TOTAL_PAGES>
J 0
(-446 18);
DISPLAY 0.978723 (-446 18);
FORCEPROP 1 LAST Q_TITLE RETIMER_CPU0_P1 POWER(6)
J 0
(-9366 26);
DISPLAY 2.446809 (-9366 26);
PAINT GREEN (-9366 26);
FORCEPROP 2 LAST PAGE_BORDER TRUE
J 0
(-7890 5250);
DISPLAY 0.638298 (-7890 5250);
PAINT PINK (-7890 5250);
DISPLAY INVISIBLE (-7890 5250);
FORCEPROP 1 LAST CDS_LMAN_SYM_OUTLINE -9475,6775,100,-125
J 0
(0 0);
DISPLAY 0.468085 (0 0);
PAINT GREEN (0 0);
DISPLAY INVISIBLE (0 0);
FORCEPROP 2 LAST CDS_LIB pure_quanta
J 0
(0 0);
DISPLAY INVISIBLE (0 0);
FORCEPROP 2 LAST CDS_XR_PAGE_TITLE CR-289 : @T6G_MB_LIB.T6G(SCH_1):PAGE289
J 0
(-7890 5250);
DISPLAY 0.638298 (-7890 5250);
PAINT PINK (-7890 5250);
DISPLAY INVISIBLE (-7890 5250);
FORCEPROP 1 LAST Q_DEPT BU9
J 1
(-3763 49);
DISPLAY 1.957447 (-3763 49);
PAINT GREEN (-3763 49);
DISPLAY INVISIBLE (-3763 49);
FORCEPROP 1 LAST COMMENT_BODY TRUE
J 0
(12 -13);
DISPLAY 0.978723 (12 -13);
PAINT GREEN (12 -13);
DISPLAY INVISIBLE (12 -13);
FORCEADD DNS..2
(-8875 3900);
PAINT RED (-8875 3900);
FORCEPROP 2 LAST CDS_LIB mstr_misc
J 0
(-8875 3900);
DISPLAY INVISIBLE (-8875 3900);
FORCEPROP 1 LAST COMMENT_BODY TRUE
J 0
(-8875 3900);
DISPLAY INVISIBLE (-8875 3900);
WIRE 16 -1 (-1675 1150)(-1675 1000);
WIRE 16 -1 (-1525 1700)(-1525 1550);
WIRE 16 -1 (-8900 4075)(-8900 4000);
WIRE 16 -1 (-7875 3250)(-7875 3150);
WIRE 16 -1 (-7325 3650)(-7875 3650);
WIRE 16 -1 (-7875 3650)(-7875 3450);
WIRE 16 -1 (-7875 3650)(-8900 3650);
FORCEPROP 2 LAST SIG_NAME RT_CPU0_P1_VQPS
J 0
(-8085 3660);
DISPLAY 0.680851 (-8085 3660);
PAINT SKYBLUE (-8085 3660);
FORCEPROP 2 LASTPROP $XRERR UNIQUE?
J 0
(-8325 3660);
DISPLAY 0.638298 (-8325 3660);
PAINT MONO (-8325 3660);
DISPLAY INVISIBLE (-8325 3660);
WIRE 16 -1 (-8900 3800)(-8900 3650);
WIRE 16 -1 (-7325 4100)(-8575 4100);
WIRE 16 -1 (-8575 4350)(-8575 4100);
WIRE 16 -1 (-5850 3600)(-5850 3550);
WIRE 16 -1 (-5850 3650)(-5850 3600);
WIRE 16 -1 (-6175 3600)(-5850 3600);
WIRE 16 -1 (-5850 3550)(-5850 3500);
WIRE 16 -1 (-6175 3550)(-5850 3550);
WIRE 16 -1 (-5850 3500)(-6175 3500);
WIRE 16 -1 (-5850 3650)(-4875 3650);
WIRE 16 -1 (-6175 3650)(-5850 3650);
WIRE 16 -1 (-4875 3750)(-4875 3650);
WIRE 16 -1 (-5950 4550)(-5950 4500);
WIRE 16 -1 (-5950 4600)(-5950 4550);
WIRE 16 -1 (-6175 4550)(-5950 4550);
WIRE 16 -1 (-5950 4500)(-6175 4500);
WIRE 16 -1 (-5950 4650)(-5950 4600);
WIRE 16 -1 (-6175 4600)(-5950 4600);
WIRE 16 -1 (-5950 4700)(-5950 4650);
WIRE 16 -1 (-6175 4650)(-5950 4650);
WIRE 16 -1 (-5950 4750)(-5950 4700);
WIRE 16 -1 (-6175 4700)(-5950 4700);
WIRE 16 -1 (-5950 4750)(-4900 4750);
WIRE 16 -1 (-6175 4750)(-5950 4750);
WIRE 16 -1 (-4900 4750)(-4900 4250);
WIRE 16 -1 (-4900 4750)(-4900 4975);
WIRE 16 -1 (-5925 4250)(-4900 4250);
WIRE 16 -1 (-5925 4250)(-5925 4200);
WIRE 16 -1 (-5925 4250)(-6175 4250);
WIRE 16 -1 (-5925 4200)(-5925 4150);
WIRE 16 -1 (-6175 4200)(-5925 4200);
WIRE 16 -1 (-5925 4150)(-5925 4100);
WIRE 16 -1 (-6175 4150)(-5925 4150);
WIRE 16 -1 (-6175 4100)(-5925 4100);
WIRE 16 -1 (-5925 4100)(-5925 4050);
WIRE 16 -1 (-5925 4050)(-5925 4000);
WIRE 16 -1 (-6175 4050)(-5925 4050);
WIRE 16 -1 (-5925 4000)(-5925 3950);
WIRE 16 -1 (-6175 4000)(-5925 4000);
WIRE 16 -1 (-5925 3950)(-5925 3900);
WIRE 16 -1 (-6175 3950)(-5925 3950);
WIRE 16 -1 (-5925 3900)(-5925 3850);
WIRE 16 -1 (-6175 3900)(-5925 3900);
WIRE 16 -1 (-5925 3850)(-5925 3800);
WIRE 16 -1 (-6175 3850)(-5925 3850);
WIRE 16 -1 (-5925 3800)(-6175 3800);
WIRE 16 -1 (-5925 4400)(-5925 4350);
WIRE 16 -1 (-5925 4450)(-5925 4400);
WIRE 16 -1 (-6175 4400)(-5925 4400);
WIRE 16 -1 (-5925 4350)(-5925 4300);
WIRE 16 -1 (-5925 4350)(-6175 4350);
WIRE 16 -1 (-5925 4300)(-6175 4300);
WIRE 16 -1 (-5925 4450)(-5475 4450);
WIRE 16 -1 (-6175 4450)(-5925 4450);
WIRE 16 -1 (-5475 4450)(-5475 4500);
WIRE 16 -1 (-3150 1575)(-3350 1575);
WIRE 16 -1 (-3350 1625)(-3350 1575);
WIRE 16 -1 (-3350 1575)(-3350 1525);
WIRE 16 -1 (-3150 1525)(-3350 1525);
WIRE 16 -1 (-3350 1525)(-3350 1375);
WIRE 16 -1 (-3150 1625)(-3350 1625);
WIRE 16 -1 (-3350 1675)(-3350 1625);
WIRE 16 -1 (-3150 1675)(-3350 1675);
WIRE 16 -1 (-3350 1725)(-3350 1675);
WIRE 16 -1 (-3150 1725)(-3350 1725);
WIRE 16 -1 (-3350 1775)(-3350 1725);
WIRE 16 -1 (-3150 1775)(-3350 1775);
WIRE 16 -1 (-3350 1825)(-3350 1775);
WIRE 16 -1 (-3150 1825)(-3350 1825);
WIRE 16 -1 (-3350 1875)(-3350 1825);
WIRE 16 -1 (-3150 1875)(-3350 1875);
WIRE 16 -1 (-3350 1925)(-3350 1875);
WIRE 16 -1 (-3150 1925)(-3350 1925);
WIRE 16 -1 (-3350 1975)(-3350 1925);
WIRE 16 -1 (-3150 1975)(-3350 1975);
WIRE 16 -1 (-3350 2025)(-3350 1975);
WIRE 16 -1 (-3350 2075)(-3350 2025);
WIRE 16 -1 (-3150 2025)(-3350 2025);
WIRE 16 -1 (-3150 2075)(-3350 2075);
WIRE 16 -1 (-3350 2125)(-3350 2075);
WIRE 16 -1 (-3150 2125)(-3350 2125);
WIRE 16 -1 (-3350 2175)(-3350 2125);
WIRE 16 -1 (-3150 2175)(-3350 2175);
WIRE 16 -1 (-3350 2225)(-3350 2175);
WIRE 16 -1 (-3150 2225)(-3350 2225);
WIRE 16 -1 (-3350 2275)(-3350 2225);
WIRE 16 -1 (-3150 2275)(-3350 2275);
WIRE 16 -1 (-3350 2325)(-3350 2275);
WIRE 16 -1 (-3150 2325)(-3350 2325);
WIRE 16 -1 (-3350 2375)(-3350 2325);
WIRE 16 -1 (-3150 2375)(-3350 2375);
WIRE 16 -1 (-3350 2425)(-3350 2375);
WIRE 16 -1 (-3150 2425)(-3350 2425);
WIRE 16 -1 (-3350 2475)(-3350 2425);
WIRE 16 -1 (-3150 2475)(-3350 2475);
WIRE 16 -1 (-3350 2525)(-3350 2475);
WIRE 16 -1 (-3350 2575)(-3350 2525);
WIRE 16 -1 (-3150 2525)(-3350 2525);
WIRE 16 -1 (-3150 2575)(-3350 2575);
WIRE 16 -1 (-3350 2625)(-3350 2575);
WIRE 16 -1 (-3150 2625)(-3350 2625);
WIRE 16 -1 (-3350 2675)(-3350 2625);
WIRE 16 -1 (-3150 2675)(-3350 2675);
WIRE 16 -1 (-3350 2725)(-3350 2675);
WIRE 16 -1 (-3150 2725)(-3350 2725);
WIRE 16 -1 (-3350 2775)(-3350 2725);
WIRE 16 -1 (-3150 2775)(-3350 2775);
WIRE 16 -1 (-3350 2825)(-3350 2775);
WIRE 16 -1 (-3150 2825)(-3350 2825);
WIRE 16 -1 (-3350 2875)(-3350 2825);
WIRE 16 -1 (-3150 2875)(-3350 2875);
WIRE 16 -1 (-3350 2925)(-3350 2875);
WIRE 16 -1 (-3150 2925)(-3350 2925);
WIRE 16 -1 (-3350 2975)(-3350 2925);
WIRE 16 -1 (-3150 2975)(-3350 2975);
WIRE 16 -1 (-3350 3025)(-3350 2975);
WIRE 16 -1 (-3350 3075)(-3350 3025);
WIRE 16 -1 (-3150 3025)(-3350 3025);
WIRE 16 -1 (-3150 3075)(-3350 3075);
WIRE 16 -1 (-3350 3125)(-3350 3075);
WIRE 16 -1 (-3150 3125)(-3350 3125);
WIRE 16 -1 (-3350 3175)(-3350 3125);
WIRE 16 -1 (-3150 3175)(-3350 3175);
WIRE 16 -1 (-3350 3225)(-3350 3175);
WIRE 16 -1 (-3150 3225)(-3350 3225);
WIRE 16 -1 (-3350 3275)(-3350 3225);
WIRE 16 -1 (-3150 3275)(-3350 3275);
WIRE 16 -1 (-3350 3325)(-3350 3275);
WIRE 16 -1 (-3150 3325)(-3350 3325);
WIRE 16 -1 (-3350 3375)(-3350 3325);
WIRE 16 -1 (-3150 3375)(-3350 3375);
WIRE 16 -1 (-3350 3425)(-3350 3375);
WIRE 16 -1 (-3150 3425)(-3350 3425);
WIRE 16 -1 (-3350 3475)(-3350 3425);
WIRE 16 -1 (-3150 3475)(-3350 3475);
WIRE 16 -1 (-3350 3525)(-3350 3475);
WIRE 16 -1 (-3150 3525)(-3350 3525);
WIRE 16 -1 (-3350 3575)(-3350 3525);
WIRE 16 -1 (-3350 3625)(-3350 3575);
WIRE 16 -1 (-3150 3575)(-3350 3575);
WIRE 16 -1 (-3150 3625)(-3350 3625);
WIRE 16 -1 (-3350 3675)(-3350 3625);
WIRE 16 -1 (-3150 3675)(-3350 3675);
WIRE 16 -1 (-3350 3725)(-3350 3675);
WIRE 16 -1 (-3150 3725)(-3350 3725);
WIRE 16 -1 (-3350 3775)(-3350 3725);
WIRE 16 -1 (-3150 3775)(-3350 3775);
WIRE 16 -1 (-3350 3825)(-3350 3775);
WIRE 16 -1 (-3150 3825)(-3350 3825);
WIRE 16 -1 (-3350 3875)(-3350 3825);
WIRE 16 -1 (-3150 3875)(-3350 3875);
WIRE 16 -1 (-3350 3925)(-3350 3875);
WIRE 16 -1 (-3150 3925)(-3350 3925);
WIRE 16 -1 (-3350 3975)(-3350 3925);
WIRE 16 -1 (-3150 3975)(-3350 3975);
WIRE 16 -1 (-3350 4025)(-3350 3975);
WIRE 16 -1 (-3150 4025)(-3350 4025);
WIRE 16 -1 (-3350 4075)(-3350 4025);
WIRE 16 -1 (-3350 4125)(-3350 4075);
WIRE 16 -1 (-3150 4075)(-3350 4075);
WIRE 16 -1 (-3150 4125)(-3350 4125);
WIRE 16 -1 (-3350 4175)(-3350 4125);
WIRE 16 -1 (-3150 4175)(-3350 4175);
WIRE 16 -1 (-3350 4225)(-3350 4175);
WIRE 16 -1 (-3150 4225)(-3350 4225);
WIRE 16 -1 (-3350 4275)(-3350 4225);
WIRE 16 -1 (-3150 4275)(-3350 4275);
WIRE 16 -1 (-3350 4325)(-3350 4275);
WIRE 16 -1 (-3150 4325)(-3350 4325);
WIRE 16 -1 (-3350 4375)(-3350 4325);
WIRE 16 -1 (-3150 4375)(-3350 4375);
WIRE 16 -1 (-3350 4425)(-3350 4375);
WIRE 16 -1 (-3150 4425)(-3350 4425);
WIRE 16 -1 (-3350 4475)(-3350 4425);
WIRE 16 -1 (-3150 4475)(-3350 4475);
WIRE 16 -1 (-3350 4525)(-3350 4475);
WIRE 16 -1 (-3150 4525)(-3350 4525);
WIRE 16 -1 (-3350 4575)(-3350 4525);
WIRE 16 -1 (-3350 4625)(-3350 4575);
WIRE 16 -1 (-3150 4575)(-3350 4575);
WIRE 16 -1 (-3150 4625)(-3350 4625);
WIRE 16 -1 (-3350 4675)(-3350 4625);
WIRE 16 -1 (-3150 4675)(-3350 4675);
WIRE 16 -1 (-3350 4725)(-3350 4675);
WIRE 16 -1 (-3150 4725)(-3350 4725);
WIRE 16 -1 (-3350 4775)(-3350 4725);
WIRE 16 -1 (-3150 4775)(-3350 4775);
WIRE 16 -1 (-3350 4825)(-3350 4775);
WIRE 16 -1 (-3150 4825)(-3350 4825);
WIRE 16 -1 (-3350 4875)(-3350 4825);
WIRE 16 -1 (-3150 4875)(-3350 4875);
WIRE 16 -1 (-3350 4925)(-3350 4875);
WIRE 16 -1 (-3150 4925)(-3350 4925);
WIRE 16 -1 (-3350 4975)(-3350 4925);
WIRE 16 -1 (-3150 4975)(-3350 4975);
WIRE 16 -1 (-3350 5025)(-3350 4975);
WIRE 16 -1 (-3150 5025)(-3350 5025);
WIRE 16 -1 (-3350 5075)(-3350 5025);
WIRE 16 -1 (-3350 5125)(-3350 5075);
WIRE 16 -1 (-3150 5075)(-3350 5075);
WIRE 16 -1 (-3150 5125)(-3350 5125);
WIRE 16 -1 (-3350 5175)(-3350 5125);
WIRE 16 -1 (-3150 5175)(-3350 5175);
WIRE 16 -1 (-3350 5225)(-3350 5175);
WIRE 16 -1 (-3150 5225)(-3350 5225);
WIRE 16 -1 (-3350 5275)(-3350 5225);
WIRE 16 -1 (-3150 5275)(-3350 5275);
WIRE 16 -1 (-3350 5325)(-3350 5275);
WIRE 16 -1 (-3150 5325)(-3350 5325);
WIRE 16 -1 (-3350 5375)(-3350 5325);
WIRE 16 -1 (-3150 5375)(-3350 5375);
WIRE 16 -1 (-3350 5425)(-3350 5375);
WIRE 16 -1 (-3150 5425)(-3350 5425);
WIRE 16 -1 (-3350 5475)(-3350 5425);
WIRE 16 -1 (-3150 5475)(-3350 5475);
WIRE 16 -1 (-3350 5525)(-3350 5475);
WIRE 16 -1 (-3150 5525)(-3350 5525);
WIRE 16 -1 (-3350 5575)(-3350 5525);
WIRE 16 -1 (-3150 5575)(-3350 5575);
WIRE 16 -1 (-2000 5575)(-2000 5525);
WIRE 16 -1 (-2000 5575)(-2200 5575);
WIRE 16 -1 (-2000 5525)(-2000 5475);
WIRE 16 -1 (-2000 5525)(-2200 5525);
WIRE 16 -1 (-2000 5475)(-2000 5425);
WIRE 16 -1 (-2000 5475)(-2200 5475);
WIRE 16 -1 (-2000 5425)(-2000 5375);
WIRE 16 -1 (-2000 5425)(-2200 5425);
WIRE 16 -1 (-2000 5375)(-2000 5325);
WIRE 16 -1 (-2000 5375)(-2200 5375);
WIRE 16 -1 (-2000 5325)(-2000 5275);
WIRE 16 -1 (-2000 5325)(-2200 5325);
WIRE 16 -1 (-2000 5275)(-2000 5225);
WIRE 16 -1 (-2000 5275)(-2200 5275);
WIRE 16 -1 (-2000 5225)(-2000 5175);
WIRE 16 -1 (-2000 5225)(-2200 5225);
WIRE 16 -1 (-2000 5175)(-2000 5125);
WIRE 16 -1 (-2000 5175)(-2200 5175);
WIRE 16 -1 (-2000 5125)(-2000 5075);
WIRE 16 -1 (-2000 5125)(-2200 5125);
WIRE 16 -1 (-2000 5075)(-2000 5025);
WIRE 16 -1 (-2000 5075)(-2200 5075);
WIRE 16 -1 (-2000 5025)(-2000 4975);
WIRE 16 -1 (-2000 5025)(-2200 5025);
WIRE 16 -1 (-2000 4975)(-2000 4925);
WIRE 16 -1 (-2000 4975)(-2200 4975);
WIRE 16 -1 (-2000 4925)(-2000 4875);
WIRE 16 -1 (-2000 4925)(-2200 4925);
WIRE 16 -1 (-2000 4875)(-2000 4825);
WIRE 16 -1 (-2000 4875)(-2200 4875);
WIRE 16 -1 (-2000 4825)(-2000 4775);
WIRE 16 -1 (-2000 4825)(-2200 4825);
WIRE 16 -1 (-2000 4775)(-2000 4725);
WIRE 16 -1 (-2000 4775)(-2200 4775);
WIRE 16 -1 (-2000 4725)(-2000 4675);
WIRE 16 -1 (-2000 4725)(-2200 4725);
WIRE 16 -1 (-2000 4675)(-2000 4625);
WIRE 16 -1 (-2000 4675)(-2200 4675);
WIRE 16 -1 (-2000 4625)(-2000 4575);
WIRE 16 -1 (-2000 4625)(-2200 4625);
WIRE 16 -1 (-2000 4575)(-2000 4525);
WIRE 16 -1 (-2000 4575)(-2200 4575);
WIRE 16 -1 (-2000 4525)(-2000 4475);
WIRE 16 -1 (-2000 4525)(-2200 4525);
WIRE 16 -1 (-2000 4475)(-2000 4425);
WIRE 16 -1 (-2000 4475)(-2200 4475);
WIRE 16 -1 (-2000 4425)(-2000 4375);
WIRE 16 -1 (-2000 4425)(-2200 4425);
WIRE 16 -1 (-2000 4375)(-2000 4325);
WIRE 16 -1 (-2000 4375)(-2200 4375);
WIRE 16 -1 (-2000 4325)(-2000 4275);
WIRE 16 -1 (-2000 4325)(-2200 4325);
WIRE 16 -1 (-2000 4275)(-2000 4225);
WIRE 16 -1 (-2000 4275)(-2200 4275);
WIRE 16 -1 (-2000 4225)(-2000 4175);
WIRE 16 -1 (-2000 4225)(-2200 4225);
WIRE 16 -1 (-2000 4175)(-2000 4125);
WIRE 16 -1 (-2000 4175)(-2200 4175);
WIRE 16 -1 (-2000 4125)(-2200 4125);
WIRE 16 -1 (-2000 4125)(-2000 4075);
WIRE 16 -1 (-2000 4075)(-2000 4025);
WIRE 16 -1 (-2000 4075)(-2200 4075);
WIRE 16 -1 (-2000 4025)(-2000 3975);
WIRE 16 -1 (-2000 4025)(-2200 4025);
WIRE 16 -1 (-2000 3975)(-2000 3925);
WIRE 16 -1 (-2000 3975)(-2200 3975);
WIRE 16 -1 (-2000 3925)(-2000 3875);
WIRE 16 -1 (-2000 3925)(-2200 3925);
WIRE 16 -1 (-2000 3875)(-2000 3825);
WIRE 16 -1 (-2000 3875)(-2200 3875);
WIRE 16 -1 (-2000 3825)(-2000 3775);
WIRE 16 -1 (-2000 3825)(-2200 3825);
WIRE 16 -1 (-2000 3775)(-2000 3725);
WIRE 16 -1 (-2000 3775)(-2200 3775);
WIRE 16 -1 (-2000 3725)(-2000 3675);
WIRE 16 -1 (-2000 3725)(-2200 3725);
WIRE 16 -1 (-2000 3675)(-2000 3625);
WIRE 16 -1 (-2000 3675)(-2200 3675);
WIRE 16 -1 (-2000 3625)(-2000 3575);
WIRE 16 -1 (-2000 3625)(-2200 3625);
WIRE 16 -1 (-2000 3575)(-2000 3525);
WIRE 16 -1 (-2000 3575)(-2200 3575);
WIRE 16 -1 (-2000 3525)(-2000 3475);
WIRE 16 -1 (-2000 3525)(-2200 3525);
WIRE 16 -1 (-2000 3475)(-2000 3425);
WIRE 16 -1 (-2000 3475)(-2200 3475);
WIRE 16 -1 (-2000 3425)(-2000 3375);
WIRE 16 -1 (-2000 3425)(-2200 3425);
WIRE 16 -1 (-2000 3375)(-2000 3325);
WIRE 16 -1 (-2000 3375)(-2200 3375);
WIRE 16 -1 (-2000 3325)(-2000 3275);
WIRE 16 -1 (-2000 3325)(-2200 3325);
WIRE 16 -1 (-2000 3275)(-2000 3225);
WIRE 16 -1 (-2000 3275)(-2200 3275);
WIRE 16 -1 (-2000 3225)(-2000 3175);
WIRE 16 -1 (-2000 3225)(-2200 3225);
WIRE 16 -1 (-2000 3175)(-2000 3125);
WIRE 16 -1 (-2000 3175)(-2200 3175);
WIRE 16 -1 (-2000 3125)(-2000 3075);
WIRE 16 -1 (-2000 3125)(-2200 3125);
WIRE 16 -1 (-2000 3075)(-2000 3025);
WIRE 16 -1 (-2000 3075)(-2200 3075);
WIRE 16 -1 (-2000 3025)(-2000 2975);
WIRE 16 -1 (-2000 3025)(-2200 3025);
WIRE 16 -1 (-2000 2975)(-2000 2925);
WIRE 16 -1 (-2000 2975)(-2200 2975);
WIRE 16 -1 (-2000 2925)(-2000 2875);
WIRE 16 -1 (-2000 2925)(-2200 2925);
WIRE 16 -1 (-2000 2875)(-2000 2825);
WIRE 16 -1 (-2000 2875)(-2200 2875);
WIRE 16 -1 (-2000 2825)(-2000 2775);
WIRE 16 -1 (-2000 2825)(-2200 2825);
WIRE 16 -1 (-2000 2775)(-2000 2725);
WIRE 16 -1 (-2000 2775)(-2200 2775);
WIRE 16 -1 (-2000 2725)(-2000 2675);
WIRE 16 -1 (-2000 2725)(-2200 2725);
WIRE 16 -1 (-2000 2675)(-2000 2625);
WIRE 16 -1 (-2000 2675)(-2200 2675);
WIRE 16 -1 (-2000 2625)(-2000 2575);
WIRE 16 -1 (-2000 2625)(-2200 2625);
WIRE 16 -1 (-2000 2575)(-2000 2525);
WIRE 16 -1 (-2000 2575)(-2200 2575);
WIRE 16 -1 (-2000 2525)(-2000 2475);
WIRE 16 -1 (-2000 2525)(-2200 2525);
WIRE 16 -1 (-2000 2475)(-2000 2425);
WIRE 16 -1 (-2000 2475)(-2200 2475);
WIRE 16 -1 (-2000 2425)(-2000 2375);
WIRE 16 -1 (-2000 2425)(-2200 2425);
WIRE 16 -1 (-2000 2375)(-2000 2325);
WIRE 16 -1 (-2000 2375)(-2200 2375);
WIRE 16 -1 (-2000 2325)(-2000 2275);
WIRE 16 -1 (-2000 2325)(-2200 2325);
WIRE 16 -1 (-2000 2275)(-2000 2225);
WIRE 16 -1 (-2000 2275)(-2200 2275);
WIRE 16 -1 (-2000 2225)(-2000 2175);
WIRE 16 -1 (-2000 2225)(-2200 2225);
WIRE 16 -1 (-2000 2175)(-2000 2150);
WIRE 16 -1 (-2000 2175)(-2200 2175);
WIRE 16 -1 (-2000 2150)(-1300 2150);
WIRE 16 -1 (-1300 2150)(-1300 2100);
WIRE 16 -1 (-1675 2025)(-1675 1975);
WIRE 16 -1 (-1675 2025)(-2200 2025);
FORCEPROP 2 LAST SIG_NAME NCF_CPU0_P1_GND
J 0
(-2085 2035);
DISPLAY 0.553191 (-2085 2035);
PAINT SKYBLUE (-2085 2035);
FORCEPROP 2 LASTPROP $XRERR UNIQUE?
J 0
(-2325 2035);
DISPLAY 0.638298 (-2325 2035);
PAINT MONO (-2325 2035);
DISPLAY INVISIBLE (-2325 2035);
WIRE 16 -1 (-1675 1975)(-1675 1925);
WIRE 16 -1 (-1675 1975)(-2200 1975);
WIRE 16 -1 (-1675 1925)(-1675 1875);
WIRE 16 -1 (-1675 1925)(-2200 1925);
WIRE 16 -1 (-1675 1875)(-1675 1825);
WIRE 16 -1 (-1675 1875)(-2200 1875);
WIRE 16 -1 (-1675 1825)(-1675 1775);
WIRE 16 -1 (-1675 1825)(-2200 1825);
WIRE 16 -1 (-1675 1775)(-1675 1725);
WIRE 16 -1 (-1675 1775)(-2200 1775);
WIRE 16 -1 (-1675 1725)(-1675 1675);
WIRE 16 -1 (-1675 1725)(-2200 1725);
WIRE 16 -1 (-1675 1675)(-1675 1625);
WIRE 16 -1 (-1675 1675)(-2200 1675);
WIRE 16 -1 (-1675 1625)(-1675 1575);
WIRE 16 -1 (-1675 1625)(-2200 1625);
WIRE 16 -1 (-1675 1575)(-1675 1525);
WIRE 16 -1 (-1675 1575)(-2200 1575);
WIRE 16 -1 (-1675 1525)(-1675 1350);
WIRE 16 -1 (-1675 1525)(-2200 1525);
WIRE 16 -1 (-7750 4550)(-7325 4550);
WIRE 16 -1 (-7750 4600)(-7750 4550);
WIRE 16 -1 (-7325 4600)(-7750 4600);
WIRE 16 -1 (-7750 4650)(-7750 4600);
WIRE 16 -1 (-7325 4650)(-7750 4650);
WIRE 16 -1 (-7750 4700)(-7750 4650);
WIRE 16 -1 (-7325 4700)(-7750 4700);
WIRE 16 -1 (-7750 4750)(-7750 4700);
WIRE 16 -1 (-7325 4750)(-7750 4750);
WIRE 16 -1 (-7750 4750)(-8000 4750);
WIRE 16 -1 (-8000 4750)(-8000 4800);
WIRE 16 -1 (-1525 2075)(-1525 1900);
WIRE 16 -1 (-2200 2075)(-1525 2075);
FORCEPROP 2 LAST SIG_NAME NCF_A1_CPU0_P1_GND
J 0
(-2035 2085);
DISPLAY 0.553191 (-2035 2085);
PAINT SKYBLUE (-2035 2085);
FORCEPROP 2 LASTPROP $XRERR UNIQUE?
J 0
(-2275 2085);
DISPLAY 0.638298 (-2275 2085);
PAINT MONO (-2275 2085);
DISPLAY INVISIBLE (-2275 2085);
DOT 1 (-5850 3550);
DOT 1 (-5925 3850);
DOT 1 (-5925 3950);
DOT 1 (-5925 4000);
DOT 1 (-5925 4050);
DOT 1 (-5850 3650);
DOT 1 (-5850 3600);
DOT 1 (-5925 4100);
DOT 1 (-7750 4600);
DOT 1 (-7750 4700);
DOT 1 (-7750 4650);
DOT 1 (-7750 4750);
DOT 1 (-5925 4200);
DOT 1 (-5925 4150);
DOT 1 (-5925 4250);
DOT 1 (-5925 4400);
DOT 1 (-5950 4550);
DOT 1 (-5950 4700);
DOT 1 (-5950 4650);
DOT 1 (-5950 4750);
DOT 1 (-4900 4750);
DOT 1 (-3350 1525);
DOT 1 (-3350 1625);
DOT 1 (-3350 1575);
DOT 1 (-3350 1675);
DOT 1 (-3350 1775);
DOT 1 (-3350 1725);
DOT 1 (-3350 1825);
DOT 1 (-3350 1875);
DOT 1 (-3350 1925);
DOT 1 (-3350 2025);
DOT 1 (-3350 1975);
DOT 1 (-3350 2175);
DOT 1 (-3350 2075);
DOT 1 (-3350 2125);
DOT 1 (-3350 2225);
DOT 1 (-3350 2275);
DOT 1 (-3350 2425);
DOT 1 (-3350 2375);
DOT 1 (-3350 2325);
DOT 1 (-3350 2525);
DOT 1 (-3350 2475);
DOT 1 (-3350 2675);
DOT 1 (-3350 2575);
DOT 1 (-3350 2625);
DOT 1 (-3350 2725);
DOT 1 (-3350 2775);
DOT 1 (-3350 2825);
DOT 1 (-3350 2875);
DOT 1 (-3350 2925);
DOT 1 (-3350 3025);
DOT 1 (-3350 2975);
DOT 1 (-3350 3075);
DOT 1 (-3350 3175);
DOT 1 (-3350 3125);
DOT 1 (-3350 3325);
DOT 1 (-3350 3275);
DOT 1 (-3350 3225);
DOT 1 (-3350 3375);
DOT 1 (-3350 3425);
DOT 1 (-3350 3575);
DOT 1 (-3350 3525);
DOT 1 (-3350 3475);
DOT 1 (-3350 3625);
DOT 1 (-3350 3675);
DOT 1 (-3350 3725);
DOT 1 (-3350 3825);
DOT 1 (-3350 3775);
DOT 1 (-3350 3875);
DOT 1 (-3350 3925);
DOT 1 (-3350 3975);
DOT 1 (-3350 4025);
DOT 1 (-3350 4075);
DOT 1 (-1675 1775);
DOT 1 (-1675 1875);
DOT 1 (-1675 1825);
DOT 1 (-1675 1925);
DOT 1 (-1675 1975);
DOT 1 (-2000 2225);
DOT 1 (-2000 2275);
DOT 1 (-2000 2325);
DOT 1 (-2000 2375);
DOT 1 (-2000 2425);
DOT 1 (-2000 2525);
DOT 1 (-2000 2575);
DOT 1 (-2000 2625);
DOT 1 (-2000 2725);
DOT 1 (-2000 2675);
DOT 1 (-2000 2775);
DOT 1 (-2000 2875);
DOT 1 (-2000 3025);
DOT 1 (-2000 2475);
DOT 1 (-2000 2825);
DOT 1 (-2000 2925);
DOT 1 (-2000 2975);
DOT 1 (-2000 2175);
DOT 1 (-2000 3075);
DOT 1 (-2000 4075);
DOT 1 (-2000 3125);
DOT 1 (-2000 3175);
DOT 1 (-2000 3225);
DOT 1 (-2000 3275);
DOT 1 (-2000 3325);
DOT 1 (-2000 3375);
DOT 1 (-2000 3425);
DOT 1 (-2000 3475);
DOT 1 (-2000 3525);
DOT 1 (-2000 3575);
DOT 1 (-2000 3625);
DOT 1 (-2000 3675);
DOT 1 (-2000 3725);
DOT 1 (-2000 3775);
DOT 1 (-2000 3825);
DOT 1 (-2000 3875);
DOT 1 (-2000 3925);
DOT 1 (-2000 3975);
DOT 1 (-2000 4025);
DOT 1 (-3350 4175);
DOT 1 (-3350 4125);
DOT 1 (-3350 4225);
DOT 1 (-3350 4325);
DOT 1 (-3350 4275);
DOT 1 (-3350 4475);
DOT 1 (-3350 4425);
DOT 1 (-3350 4375);
DOT 1 (-3350 4575);
DOT 1 (-3350 4525);
DOT 1 (-3350 4725);
DOT 1 (-3350 4625);
DOT 1 (-3350 4675);
DOT 1 (-3350 4825);
DOT 1 (-3350 4875);
DOT 1 (-3350 4975);
DOT 1 (-3350 4925);
DOT 1 (-3350 5075);
DOT 1 (-3350 5025);
DOT 1 (-3350 5125);
DOT 1 (-3350 5225);
DOT 1 (-3350 5275);
DOT 1 (-3350 5325);
DOT 1 (-3350 5375);
DOT 1 (-3350 5425);
DOT 1 (-3350 5475);
DOT 1 (-2000 4125);
DOT 1 (-2000 4175);
DOT 1 (-2000 4225);
DOT 1 (-2000 4275);
DOT 1 (-2000 4325);
DOT 1 (-2000 4375);
DOT 1 (-2000 4425);
DOT 1 (-2000 4475);
DOT 1 (-2000 4525);
DOT 1 (-2000 4575);
DOT 1 (-2000 4625);
DOT 1 (-2000 4675);
DOT 1 (-2000 4725);
DOT 1 (-2000 4775);
DOT 1 (-2000 4825);
DOT 1 (-2000 4875);
DOT 1 (-2000 4925);
DOT 1 (-2000 4975);
DOT 1 (-2000 5025);
DOT 1 (-2000 5075);
DOT 1 (-2000 5125);
DOT 1 (-2000 5375);
DOT 1 (-2000 5175);
DOT 1 (-2000 5225);
DOT 1 (-2000 5275);
DOT 1 (-2000 5325);
DOT 1 (-2000 5425);
DOT 1 (-2000 5475);
DOT 1 (-2000 5525);
DOT 1 (-5925 3900);
DOT 1 (-3350 5175);
DOT 1 (-3350 5525);
DOT 1 (-5950 4600);
DOT 1 (-5925 4350);
DOT 1 (-1675 1725);
DOT 1 (-1675 1675);
DOT 1 (-1675 1625);
DOT 1 (-1675 1575);
DOT 1 (-1675 1525);
DOT 1 (-3350 4775);
DOT 1 (-5925 4450);
DOT 1 (-7875 3650);
QUIT
